# BASEBOARD_FAB2 (Tioga Pass) — schematic netlist excerpt (pin names and nets, part order shuffled) for the footprints in the layout excerpt that follows; sources: Cadence DE-HDL packaged netlist, KiCad conversion of Wiwynn_Tioga_Pass_MB.brd

C25W100  CAP_A  0.1UF 16V 10% X7R  pkg 0402V  page 255 : A = P3V3_STBY ; B = GND
C1R18  CAP_A  0.1UF 16V 10% X7R  pkg 0402V  page 139 : A = P0V9_LAN ; B = GND
R1U20  RES  20.0 1% CHIP  pkg 0402  page 159 : A = SMB_SMLINK0_STBY_LVC3_SDA ; B = SMB_SPRINGVILLE_STBY_LVC3_SDA

(kicad_pcb
	(version 20260206)
	(generator "pcbnew")
	(generator_version "10.0")
	(general
		(thickness 1.6)
		(legacy_teardrops no)
	)
	(paper "A4")
	(title_block
		(title "Wiwynn_Tioga_Pass_MB.brd")
		(comment 1 "Tioga Pass / footprints 4429-4431 of 4770")
	)
	(layers
		(0 "F.Cu" signal "TOP")
		(4 "In1.Cu" signal "L2GND")
		(6 "In2.Cu" signal "L3")
		(8 "In3.Cu" signal "L4GND")
		(10 "In4.Cu" signal "L5")
		(12 "In5.Cu" signal "L6GND")
		(14 "In6.Cu" signal "L7VCC")
		(16 "In7.Cu" signal "L8VCC")
		(18 "In8.Cu" signal "L9GND")
		(20 "In9.Cu" signal "L10")
		(22 "In10.Cu" signal "L11GND")
		(24 "In11.Cu" signal "L12")
		(26 "In12.Cu" signal "L13GND")
		(2 "B.Cu" signal "BOTTOM")
		(9 "F.Adhes" user "F.Adhesive")
		(11 "B.Adhes" user "B.Adhesive")
		(13 "F.Paste" user "Package Geometry/Pastemask Top")
		(15 "B.Paste" user "Package Geometry/Pastemask Bottom")
		(5 "F.SilkS" user "Ref Des/Silkscreen Top")
		(7 "B.SilkS" user "Ref Des/Silkscreen Bottom")
		(1 "F.Mask" user "Board Geometry/Soldermask Top")
		(3 "B.Mask" user "Board Geometry/Soldermask Bottom")
		(17 "Dwgs.User" user "User.Drawings")
		(19 "Cmts.User" user "User.Comments")
		(21 "Eco1.User" user "User.Eco1")
		(23 "Eco2.User" user "User.Eco2")
		(25 "Edge.Cuts" user "Board Geometry/Outline")
		(27 "Margin" user)
		(31 "F.CrtYd" user "Package Geometry/Place Bound Top")
		(29 "B.CrtYd" user "Package Geometry/Place Bound Bottom")
		(35 "F.Fab" user "Ref Des/Assembly Top")
		(33 "B.Fab" user "Ref Des/Assembly Bottom")
	)
	(footprint ""
		(layer "B.Cu")
		(at 485.0892 -128.2065 180)
		(property "Reference" "R1U20"
			(at 0 0 0)
			(layer "B.SilkS")
			(hide yes)
			(effects
				(font
					(size 1.27 1.27)
				)
				(justify mirror)
			)
		)
		(property "Value" ""
			(at 0 0 0)
			(layer "B.Fab")
			(effects
				(font
					(size 1.27 1.27)
				)
				(justify mirror)
			)
		)
		(duplicate_pad_numbers_are_jumpers no)
		(fp_poly
			(pts
				(xy 0.2794 -0.1016) (xy -0.2794 -0.1016) (xy -0.2794 0.9906) (xy 0.2794 0.9906)
			)
			(stroke
				(width 0)
				(type default)
			)
			(fill no)
			(layer "B.CrtYd")
		)
		(fp_line
			(start 0.2794 0.9906)
			(end -0.2794 0.9906)
			(stroke
				(width 0.1)
				(type default)
			)
			(layer "B.Fab")
		)
		(fp_line
			(start 0.2794 -0.1016)
			(end 0.2794 0.9906)
			(stroke
				(width 0.1)
				(type default)
			)
			(layer "B.Fab")
		)
		(fp_line
			(start -0.2794 0.9906)
			(end -0.2794 -0.1016)
			(stroke
				(width 0.1)
				(type default)
			)
			(layer "B.Fab")
		)
		(fp_line
			(start -0.2794 -0.1016)
			(end 0.2794 -0.1016)
			(stroke
				(width 0.1)
				(type default)
			)
			(layer "B.Fab")
		)
		(pad "1" smd rect
			(at 0 0)
			(size 0.508 0.508)
			(layers "B.Cu" "B.Mask" "B.Paste")
			(net "SMB_SMLINK0_STBY_LVC3_SDA")
		)
		(pad "2" smd rect
			(at 0 0.889)
			(size 0.508 0.508)
			(layers "B.Cu" "B.Mask" "B.Paste")
			(net "SMB_SPRINGVILLE_STBY_LVC3_SDA")
		)
		(zone
			(layer "B.Cu")
			(hatch none 0.5)
			(connect_pads
				(clearance 0)
			)
			(min_thickness 0.25)
			(keepout
				(tracks not_allowed)
				(vias allowed)
				(pads allowed)
				(copperpour not_allowed)
				(footprints allowed)
			)
			(placement
				(enabled no)
				(sheetname "")
			)
			(fill
				(thermal_gap 0.5)
				(thermal_bridge_width 0.5)
				(island_removal_mode 0)
			)
			(polygon
				(pts
					(xy 484.8352 -128.8415) (xy 485.3432 -128.8415) (xy 485.3432 -128.4605) (xy 484.8352 -128.4605)
				)
			)
		)
		(zone
			(layer "B.Cu")
			(hatch none 0.5)
			(connect_pads
				(clearance 0)
			)
			(min_thickness 0.25)
			(keepout
				(tracks allowed)
				(vias not_allowed)
				(pads allowed)
				(copperpour not_allowed)
				(footprints allowed)
			)
			(placement
				(enabled no)
				(sheetname "")
			)
			(fill
				(thermal_gap 0.5)
				(thermal_bridge_width 0.5)
				(island_removal_mode 0)
			)
			(polygon
				(pts
					(xy 484.8352 -128.4605) (xy 485.3432 -128.4605) (xy 485.3432 -128.8415) (xy 484.8352 -128.8415)
				)
			)
		)
	)
	(footprint ""
		(layer "B.Cu")
		(at 488.181396 -44.48556 -90)
		(property "Reference" "C1R18"
			(at 0 0 90)
			(layer "B.SilkS")
			(hide yes)
			(effects
				(font
					(size 1.27 1.27)
				)
				(justify mirror)
			)
		)
		(property "Value" ""
			(at 0 0 90)
			(layer "B.Fab")
			(effects
				(font
					(size 1.27 1.27)
				)
				(justify mirror)
			)
		)
		(duplicate_pad_numbers_are_jumpers no)
		(fp_poly
			(pts
				(xy -0.3048 -0.1016) (xy -0.3048 0.9906) (xy 0.3048 0.9906) (xy 0.3048 -0.1016)
			)
			(stroke
				(width 0)
				(type default)
			)
			(fill no)
			(layer "B.CrtYd")
		)
		(fp_line
			(start -0.3048 0.9906)
			(end -0.3048 -0.1016)
			(stroke
				(width 0.1)
				(type default)
			)
			(layer "B.Fab")
		)
		(fp_line
			(start 0.3048 0.9906)
			(end -0.3048 0.9906)
			(stroke
				(width 0.1)
				(type default)
			)
			(layer "B.Fab")
		)
		(fp_line
			(start -0.3048 -0.1016)
			(end 0.3048 -0.1016)
			(stroke
				(width 0.1)
				(type default)
			)
			(layer "B.Fab")
		)
		(fp_line
			(start 0.3048 -0.1016)
			(end 0.3048 0.9906)
			(stroke
				(width 0.1)
				(type default)
			)
			(layer "B.Fab")
		)
		(pad "1" smd rect
			(at 0 0 90)
			(size 0.508 0.508)
			(layers "B.Cu" "B.Mask" "B.Paste")
			(net "P0V9_LAN")
		)
		(pad "2" smd rect
			(at 0 0.889 90)
			(size 0.508 0.508)
			(layers "B.Cu" "B.Mask" "B.Paste")
			(net "GND")
		)
		(zone
			(layer "B.Cu")
			(hatch none 0.5)
			(connect_pads
				(clearance 0)
			)
			(min_thickness 0.25)
			(keepout
				(tracks not_allowed)
				(vias allowed)
				(pads allowed)
				(copperpour not_allowed)
				(footprints allowed)
			)
			(placement
				(enabled no)
				(sheetname "")
			)
			(fill
				(thermal_gap 0.5)
				(thermal_bridge_width 0.5)
				(island_removal_mode 0)
			)
			(polygon
				(pts
					(xy 487.546396 -44.23156) (xy 487.546396 -44.73956) (xy 487.927396 -44.73956) (xy 487.927396 -44.23156)
				)
			)
		)
		(zone
			(layer "B.Cu")
			(hatch none 0.5)
			(connect_pads
				(clearance 0)
			)
			(min_thickness 0.25)
			(keepout
				(tracks allowed)
				(vias not_allowed)
				(pads allowed)
				(copperpour not_allowed)
				(footprints allowed)
			)
			(placement
				(enabled no)
				(sheetname "")
			)
			(fill
				(thermal_gap 0.5)
				(thermal_bridge_width 0.5)
				(island_removal_mode 0)
			)
			(polygon
				(pts
					(xy 487.927396 -44.23156) (xy 487.927396 -44.73956) (xy 487.546396 -44.73956) (xy 487.546396 -44.23156)
				)
			)
		)
	)
	(footprint ""
		(layer "B.Cu")
		(at 449.172838 -155.848812 90)
		(property "Reference" "C25W100"
			(at 0.8382 -0.67818 90)
			(unlocked yes)
			(layer "B.SilkS")
			(effects
				(font
					(size 0.4064 0.254)
					(thickness 0.1524)
				)
				(justify left mirror)
			)
		)
		(property "Value" ""
			(at 0 0 90)
			(layer "B.Fab")
			(effects
				(font
					(size 1.27 1.27)
				)
				(justify mirror)
			)
		)
		(duplicate_pad_numbers_are_jumpers no)
		(fp_poly
			(pts
				(xy -0.3048 -0.1016) (xy -0.3048 0.9906) (xy 0.3048 0.9906) (xy 0.3048 -0.1016)
			)
			(stroke
				(width 0)
				(type default)
			)
			(fill no)
			(layer "B.CrtYd")
		)
		(fp_line
			(start 0.3048 -0.1016)
			(end 0.3048 0.9906)
			(stroke
				(width 0.1)
				(type default)
			)
			(layer "B.Fab")
		)
		(fp_line
			(start -0.3048 -0.1016)
			(end 0.3048 -0.1016)
			(stroke
				(width 0.1)
				(type default)
			)
			(layer "B.Fab")
		)
		(fp_line
			(start 0.3048 0.9906)
			(end -0.3048 0.9906)
			(stroke
				(width 0.1)
				(type default)
			)
			(layer "B.Fab")
		)
		(fp_line
			(start -0.3048 0.9906)
			(end -0.3048 -0.1016)
			(stroke
				(width 0.1)
				(type default)
			)
			(layer "B.Fab")
		)
		(pad "1" smd rect
			(at 0 0 270)
			(size 0.508 0.508)
			(layers "B.Cu" "B.Mask" "B.Paste")
			(net "P3V3_STBY")
		)
		(pad "2" smd rect
			(at 0 0.889 270)
			(size 0.508 0.508)
			(layers "B.Cu" "B.Mask" "B.Paste")
			(net "GND")
		)
		(zone
			(layer "B.Cu")
			(hatch none 0.5)
			(connect_pads
				(clearance 0)
			)
			(min_thickness 0.25)
			(keepout
				(tracks allowed)
				(vias not_allowed)
				(pads allowed)
				(copperpour not_allowed)
				(footprints allowed)
			)
			(placement
				(enabled no)
				(sheetname "")
			)
			(fill
				(thermal_gap 0.5)
				(thermal_bridge_width 0.5)
				(island_removal_mode 0)
			)
			(polygon
				(pts
					(xy 449.426838 -156.102812) (xy 449.426838 -155.594812) (xy 449.807838 -155.594812) (xy 449.807838 -156.102812)
				)
			)
		)
		(zone
			(layer "B.Cu")
			(hatch none 0.5)
			(connect_pads
				(clearance 0)
			)
			(min_thickness 0.25)
			(keepout
				(tracks not_allowed)
				(vias allowed)
				(pads allowed)
				(copperpour not_allowed)
				(footprints allowed)
			)
			(placement
				(enabled no)
				(sheetname "")
			)
			(fill
				(thermal_gap 0.5)
				(thermal_bridge_width 0.5)
				(island_removal_mode 0)
			)
			(polygon
				(pts
					(xy 449.807838 -156.102812) (xy 449.807838 -155.594812) (xy 449.426838 -155.594812) (xy 449.426838 -156.102812)
				)
			)
		)
	)
)
